(kicad_pcb
	(version 20241229)
	(generator "pcbnew")
	(generator_version "9.0")
	(general
		(thickness 1.61)
		(legacy_teardrops no)
	)
	(paper "A3")
	(title_block
		(title "SO-DIMM DDR5 Tester")
		(date "2025-11-26")
		(rev "1.3.0")
		(comment 9 "footprints 27-32 of 627")
	)
	(layers
		(0 "F.Cu" signal)
		(4 "In1.Cu" power)
		(6 "In2.Cu" mixed)
		(8 "In3.Cu" power)
		(10 "In4.Cu" mixed)
		(12 "In5.Cu" power)
		(14 "In6.Cu" mixed)
		(16 "In7.Cu" power)
		(18 "In8.Cu" power)
		(20 "In9.Cu" mixed)
		(22 "In10.Cu" power)
		(2 "B.Cu" signal)
		(9 "F.Adhes" user "F.Adhesive")
		(11 "B.Adhes" user "B.Adhesive")
		(13 "F.Paste" user)
		(15 "B.Paste" user)
		(5 "F.SilkS" user "F.Silkscreen")
		(7 "B.SilkS" user "B.Silkscreen")
		(1 "F.Mask" user)
		(3 "B.Mask" user)
		(17 "Dwgs.User" user "User.Drawings")
		(19 "Cmts.User" user "User.Comments")
		(21 "Eco1.User" user "User.Eco1")
		(23 "Eco2.User" user "User.Eco2")
		(25 "Edge.Cuts" user)
		(27 "Margin" user)
		(31 "F.CrtYd" user "F.Courtyard")
		(29 "B.CrtYd" user "B.Courtyard")
		(35 "F.Fab" user)
		(33 "B.Fab" user)
	)
	(footprint "antmicro-footprints:C_0402_1005Metric"
		(layer "F.Cu")
		(at 100.900501 158.958851)
		(descr "Capacitor SMD 0402")
		(tags "capacitor SMD 0402")
		(property "Reference" "C139"
			(at 0 -0.699 0)
			(layer "F.SilkS")
			(hide yes)
			(effects
				(font
					(size 0.7 0.7)
					(thickness 0.15)
				)
				(justify left bottom)
			)
		)
		(property "Value" "C_4u7_0402"
			(at -1.022927 2.155213 0)
			(layer "F.Fab")
			(effects
				(font
					(size 0.7 0.7)
					(thickness 0.15)
				)
				(justify left bottom)
			)
		)
		(property "Datasheet" "https://www.murata.com/products/productdetail?partno=GRM155R61A475MEAA%23"
			(at 0 0 0)
			(layer "F.Fab")
			(hide yes)
			(effects
				(font
					(size 1.27 1.27)
					(thickness 0.15)
				)
			)
		)
		(property "Author" "Antmicro"
			(at 0 0 0)
			(layer "F.Fab")
			(hide yes)
			(effects
				(font
					(size 1 1)
					(thickness 0.15)
				)
			)
		)
		(property "Dielectric" ""
			(at 0 0 0)
			(layer "F.Fab")
			(hide yes)
			(effects
				(font
					(size 1 1)
					(thickness 0.15)
				)
			)
		)
		(property "License" "Apache-2.0"
			(at 0 0 0)
			(layer "F.Fab")
			(hide yes)
			(effects
				(font
					(size 1 1)
					(thickness 0.15)
				)
			)
		)
		(property "MPN" "GRM155R61A475MEAAD"
			(at 0 0 0)
			(layer "F.Fab")
			(hide yes)
			(effects
				(font
					(size 1 1)
					(thickness 0.15)
				)
			)
		)
		(property "Manufacturer" "Murata"
			(at 0 0 0)
			(layer "F.Fab")
			(hide yes)
			(effects
				(font
					(size 1 1)
					(thickness 0.15)
				)
			)
		)
		(property "Val" "4u7"
			(at 0 0 0)
			(layer "F.Fab")
			(hide yes)
			(effects
				(font
					(size 1 1)
					(thickness 0.15)
				)
			)
		)
		(property "Voltage" ""
			(at 0 0 0)
			(layer "F.Fab")
			(hide yes)
			(effects
				(font
					(size 1 1)
					(thickness 0.15)
				)
			)
		)
		(sheetname "/Ethernet/")
		(sheetfile "ethernet.kicad_sch")
		(attr smd)
		(fp_rect
			(start -0.9659 -0.481258)
			(end 0.9649 0.458742)
			(stroke
				(width 0.05)
				(type solid)
			)
			(fill no)
			(layer "F.CrtYd")
		)
		(fp_line
			(start -0.499 -0.25)
			(end 0.499 -0.25)
			(stroke
				(width 0.15)
				(type solid)
			)
			(layer "F.Fab")
		)
		(fp_line
			(start -0.499 0.248)
			(end -0.499 -0.25)
			(stroke
				(width 0.15)
				(type solid)
			)
			(layer "F.Fab")
		)
		(fp_line
			(start 0.499 -0.25)
			(end 0.499 0.248)
			(stroke
				(width 0.15)
				(type solid)
			)
			(layer "F.Fab")
		)
		(fp_line
			(start 0.499 0.248)
			(end -0.499 0.248)
			(stroke
				(width 0.15)
				(type solid)
			)
			(layer "F.Fab")
		)
		(pad "1" smd roundrect
			(at -0.484 0)
			(size 0.59 0.64)
			(layers "F.Cu" "F.Mask" "F.Paste")
			(roundrect_rratio 0.25)
			(net 199 "+1V2")
			(pintype "passive")
		)
		(pad "2" smd roundrect
			(at 0.484 0)
			(size 0.59 0.64)
			(layers "F.Cu" "F.Mask" "F.Paste")
			(roundrect_rratio 0.25)
			(net 1 "GND")
			(pintype "passive")
		)
	)
	(footprint "antmicro-footprints:C_0402_1005Metric"
		(layer "F.Cu")
		(at 100.900501 157.958851)
		(descr "Capacitor SMD 0402")
		(tags "capacitor SMD 0402")
		(property "Reference" "C142"
			(at 0 -0.699 0)
			(layer "F.SilkS")
			(hide yes)
			(effects
				(font
					(size 0.7 0.7)
					(thickness 0.15)
				)
				(justify left bottom)
			)
		)
		(property "Value" "C_470n_0402"
			(at -1.022927 2.155213 0)
			(layer "F.Fab")
			(effects
				(font
					(size 0.7 0.7)
					(thickness 0.15)
				)
				(justify left bottom)
			)
		)
		(property "Datasheet" "https://product.tdk.com/en/search/capacitor/ceramic/mlcc/info?part_no=C1005X5R1E474M050BB"
			(at 0 0 0)
			(layer "F.Fab")
			(hide yes)
			(effects
				(font
					(size 1.27 1.27)
					(thickness 0.15)
				)
			)
		)
		(property "Author" "Antmicro"
			(at 0 0 0)
			(layer "F.Fab")
			(hide yes)
			(effects
				(font
					(size 1 1)
					(thickness 0.15)
				)
			)
		)
		(property "Dielectric" ""
			(at 0 0 0)
			(layer "F.Fab")
			(hide yes)
			(effects
				(font
					(size 1 1)
					(thickness 0.15)
				)
			)
		)
		(property "License" "Apache-2.0"
			(at 0 0 0)
			(layer "F.Fab")
			(hide yes)
			(effects
				(font
					(size 1 1)
					(thickness 0.15)
				)
			)
		)
		(property "MPN" "C1005X5R1E474M050BB"
			(at 0 0 0)
			(layer "F.Fab")
			(hide yes)
			(effects
				(font
					(size 1 1)
					(thickness 0.15)
				)
			)
		)
		(property "Manufacturer" "TDK"
			(at 0 0 0)
			(layer "F.Fab")
			(hide yes)
			(effects
				(font
					(size 1 1)
					(thickness 0.15)
				)
			)
		)
		(property "Val" "470n"
			(at 0 0 0)
			(layer "F.Fab")
			(hide yes)
			(effects
				(font
					(size 1 1)
					(thickness 0.15)
				)
			)
		)
		(property "Voltage" ""
			(at 0 0 0)
			(layer "F.Fab")
			(hide yes)
			(effects
				(font
					(size 1 1)
					(thickness 0.15)
				)
			)
		)
		(sheetname "/Ethernet/")
		(sheetfile "ethernet.kicad_sch")
		(attr smd)
		(fp_rect
			(start -0.9659 -0.481258)
			(end 0.9649 0.458742)
			(stroke
				(width 0.05)
				(type solid)
			)
			(fill no)
			(layer "F.CrtYd")
		)
		(fp_line
			(start -0.499 -0.25)
			(end 0.499 -0.25)
			(stroke
				(width 0.15)
				(type solid)
			)
			(layer "F.Fab")
		)
		(fp_line
			(start -0.499 0.248)
			(end -0.499 -0.25)
			(stroke
				(width 0.15)
				(type solid)
			)
			(layer "F.Fab")
		)
		(fp_line
			(start 0.499 -0.25)
			(end 0.499 0.248)
			(stroke
				(width 0.15)
				(type solid)
			)
			(layer "F.Fab")
		)
		(fp_line
			(start 0.499 0.248)
			(end -0.499 0.248)
			(stroke
				(width 0.15)
				(type solid)
			)
			(layer "F.Fab")
		)
		(pad "1" smd roundrect
			(at -0.484 0)
			(size 0.59 0.64)
			(layers "F.Cu" "F.Mask" "F.Paste")
			(roundrect_rratio 0.25)
			(net 199 "+1V2")
			(pintype "passive")
		)
		(pad "2" smd roundrect
			(at 0.484 0)
			(size 0.59 0.64)
			(layers "F.Cu" "F.Mask" "F.Paste")
			(roundrect_rratio 0.25)
			(net 1 "GND")
			(pintype "passive")
		)
	)
	(footprint "antmicro-footprints:C_0402_1005Metric"
		(layer "F.Cu")
		(at 100.400501 156.458851 90)
		(descr "Capacitor SMD 0402")
		(tags "capacitor SMD 0402")
		(property "Reference" "C159"
			(at 0 -0.699 90)
			(layer "F.SilkS")
			(hide yes)
			(effects
				(font
					(size 0.7 0.7)
					(thickness 0.15)
				)
				(justify left bottom)
			)
		)
		(property "Value" "C_4u7_0402"
			(at -1.022927 2.155213 90)
			(layer "F.Fab")
			(effects
				(font
					(size 0.7 0.7)
					(thickness 0.15)
				)
				(justify left bottom)
			)
		)
		(property "Datasheet" "https://www.murata.com/products/productdetail?partno=GRM155R61A475MEAA%23"
			(at 0 0 90)
			(layer "F.Fab")
			(hide yes)
			(effects
				(font
					(size 1.27 1.27)
					(thickness 0.15)
				)
			)
		)
		(property "Author" "Antmicro"
			(at 256.859352 56.05835 0)
			(layer "F.Fab")
			(hide yes)
			(effects
				(font
					(size 1 1)
					(thickness 0.15)
				)
			)
		)
		(property "Dielectric" ""
			(at 256.859352 56.05835 0)
			(layer "F.Fab")
			(hide yes)
			(effects
				(font
					(size 1 1)
					(thickness 0.15)
				)
			)
		)
		(property "License" "Apache-2.0"
			(at 256.859352 56.05835 0)
			(layer "F.Fab")
			(hide yes)
			(effects
				(font
					(size 1 1)
					(thickness 0.15)
				)
			)
		)
		(property "MPN" "GRM155R61A475MEAAD"
			(at 256.859352 56.05835 0)
			(layer "F.Fab")
			(hide yes)
			(effects
				(font
					(size 1 1)
					(thickness 0.15)
				)
			)
		)
		(property "Manufacturer" "Murata"
			(at 256.859352 56.05835 0)
			(layer "F.Fab")
			(hide yes)
			(effects
				(font
					(size 1 1)
					(thickness 0.15)
				)
			)
		)
		(property "Val" "4u7"
			(at 256.859352 56.05835 0)
			(layer "F.Fab")
			(hide yes)
			(effects
				(font
					(size 1 1)
					(thickness 0.15)
				)
			)
		)
		(property "Voltage" ""
			(at 256.859352 56.05835 0)
			(layer "F.Fab")
			(hide yes)
			(effects
				(font
					(size 1 1)
					(thickness 0.15)
				)
			)
		)
		(sheetname "/Ethernet/")
		(sheetfile "ethernet.kicad_sch")
		(attr smd)
		(fp_rect
			(start -0.9659 -0.481258)
			(end 0.9649 0.458742)
			(stroke
				(width 0.05)
				(type solid)
			)
			(fill no)
			(layer "F.CrtYd")
		)
		(fp_line
			(start 0.499 -0.25)
			(end 0.499 0.248)
			(stroke
				(width 0.15)
				(type solid)
			)
			(layer "F.Fab")
		)
		(fp_line
			(start -0.499 -0.25)
			(end 0.499 -0.25)
			(stroke
				(width 0.15)
				(type solid)
			)
			(layer "F.Fab")
		)
		(fp_line
			(start 0.499 0.248)
			(end -0.499 0.248)
			(stroke
				(width 0.15)
				(type solid)
			)
			(layer "F.Fab")
		)
		(fp_line
			(start -0.499 0.248)
			(end -0.499 -0.25)
			(stroke
				(width 0.15)
				(type solid)
			)
			(layer "F.Fab")
		)
		(pad "1" smd roundrect
			(at -0.484 0 90)
			(size 0.59 0.64)
			(layers "F.Cu" "F.Mask" "F.Paste")
			(roundrect_rratio 0.25)
			(net 1 "GND")
			(pintype "passive")
		)
		(pad "2" smd roundrect
			(at 0.484 0 90)
			(size 0.59 0.64)
			(layers "F.Cu" "F.Mask" "F.Paste")
			(roundrect_rratio 0.25)
			(net 133 "/Ethernet/AVDDL_PLL")
			(pintype "passive")
		)
	)
	(footprint "antmicro-footprints:C_0402_1005Metric"
		(layer "F.Cu")
		(at 88.500501 154.058851 -90)
		(descr "Capacitor SMD 0402")
		(tags "capacitor SMD 0402")
		(property "Reference" "C138"
			(at 0 -0.699 270)
			(layer "F.SilkS")
			(hide yes)
			(effects
				(font
					(size 0.7 0.7)
					(thickness 0.15)
				)
				(justify left bottom)
			)
		)
		(property "Value" "C_470n_0402"
			(at -1.022927 2.155213 270)
			(layer "F.Fab")
			(effects
				(font
					(size 0.7 0.7)
					(thickness 0.15)
				)
				(justify left bottom)
			)
		)
		(property "Datasheet" "https://product.tdk.com/en/search/capacitor/ceramic/mlcc/info?part_no=C1005X5R1E474M050BB"
			(at 0 0 270)
			(layer "F.Fab")
			(hide yes)
			(effects
				(font
					(size 1.27 1.27)
					(thickness 0.15)
				)
			)
		)
		(property "Author" "Antmicro"
			(at -65.55835 242.559352 0)
			(layer "F.Fab")
			(hide yes)
			(effects
				(font
					(size 1 1)
					(thickness 0.15)
				)
			)
		)
		(property "Dielectric" ""
			(at -65.55835 242.559352 0)
			(layer "F.Fab")
			(hide yes)
			(effects
				(font
					(size 1 1)
					(thickness 0.15)
				)
			)
		)
		(property "License" "Apache-2.0"
			(at -65.55835 242.559352 0)
			(layer "F.Fab")
			(hide yes)
			(effects
				(font
					(size 1 1)
					(thickness 0.15)
				)
			)
		)
		(property "MPN" "C1005X5R1E474M050BB"
			(at -65.55835 242.559352 0)
			(layer "F.Fab")
			(hide yes)
			(effects
				(font
					(size 1 1)
					(thickness 0.15)
				)
			)
		)
		(property "Manufacturer" "TDK"
			(at -65.55835 242.559352 0)
			(layer "F.Fab")
			(hide yes)
			(effects
				(font
					(size 1 1)
					(thickness 0.15)
				)
			)
		)
		(property "Val" "470n"
			(at -65.55835 242.559352 0)
			(layer "F.Fab")
			(hide yes)
			(effects
				(font
					(size 1 1)
					(thickness 0.15)
				)
			)
		)
		(property "Voltage" ""
			(at -65.55835 242.559352 0)
			(layer "F.Fab")
			(hide yes)
			(effects
				(font
					(size 1 1)
					(thickness 0.15)
				)
			)
		)
		(sheetname "/Ethernet/")
		(sheetfile "ethernet.kicad_sch")
		(attr smd)
		(fp_rect
			(start -0.9659 -0.481258)
			(end 0.9649 0.458742)
			(stroke
				(width 0.05)
				(type solid)
			)
			(fill no)
			(layer "F.CrtYd")
		)
		(fp_line
			(start -0.499 0.248)
			(end -0.499 -0.25)
			(stroke
				(width 0.15)
				(type solid)
			)
			(layer "F.Fab")
		)
		(fp_line
			(start 0.499 0.248)
			(end -0.499 0.248)
			(stroke
				(width 0.15)
				(type solid)
			)
			(layer "F.Fab")
		)
		(fp_line
			(start -0.499 -0.25)
			(end 0.499 -0.25)
			(stroke
				(width 0.15)
				(type solid)
			)
			(layer "F.Fab")
		)
		(fp_line
			(start 0.499 -0.25)
			(end 0.499 0.248)
			(stroke
				(width 0.15)
				(type solid)
			)
			(layer "F.Fab")
		)
		(pad "1" smd roundrect
			(at -0.484 0 270)
			(size 0.59 0.64)
			(layers "F.Cu" "F.Mask" "F.Paste")
			(roundrect_rratio 0.25)
			(net 200 "+3V3")
			(pintype "passive")
		)
		(pad "2" smd roundrect
			(at 0.484 0 270)
			(size 0.59 0.64)
			(layers "F.Cu" "F.Mask" "F.Paste")
			(roundrect_rratio 0.25)
			(net 1 "GND")
			(pintype "passive")
		)
	)
	(footprint "antmicro-footprints:C_0402_1005Metric"
		(layer "F.Cu")
		(at 101.500501 156.458851 90)
		(descr "Capacitor SMD 0402")
		(tags "capacitor SMD 0402")
		(property "Reference" "C157"
			(at 0 -0.699 90)
			(layer "F.SilkS")
			(hide yes)
			(effects
				(font
					(size 0.7 0.7)
					(thickness 0.15)
				)
				(justify left bottom)
			)
		)
		(property "Value" "C_100n_0402"
			(at -1.022927 2.155213 90)
			(layer "F.Fab")
			(effects
				(font
					(size 0.7 0.7)
					(thickness 0.15)
				)
				(justify left bottom)
			)
		)
		(property "Datasheet" "https://www.murata.com/products/productdetail?partno=GRM155R61H104KE14%23"
			(at 0 0 90)
			(layer "F.Fab")
			(hide yes)
			(effects
				(font
					(size 1.27 1.27)
					(thickness 0.15)
				)
			)
		)
		(property "Author" "Antmicro"
			(at 257.959352 54.95835 0)
			(layer "F.Fab")
			(hide yes)
			(effects
				(font
					(size 1 1)
					(thickness 0.15)
				)
			)
		)
		(property "Dielectric" "X5R"
			(at 257.959352 54.95835 0)
			(layer "F.Fab")
			(hide yes)
			(effects
				(font
					(size 1 1)
					(thickness 0.15)
				)
			)
		)
		(property "License" "Apache-2.0"
			(at 257.959352 54.95835 0)
			(layer "F.Fab")
			(hide yes)
			(effects
				(font
					(size 1 1)
					(thickness 0.15)
				)
			)
		)
		(property "MPN" "GRM155R61H104KE14D"
			(at 257.959352 54.95835 0)
			(layer "F.Fab")
			(hide yes)
			(effects
				(font
					(size 1 1)
					(thickness 0.15)
				)
			)
		)
		(property "Manufacturer" "Murata"
			(at 257.959352 54.95835 0)
			(layer "F.Fab")
			(hide yes)
			(effects
				(font
					(size 1 1)
					(thickness 0.15)
				)
			)
		)
		(property "Val" "100n"
			(at 257.959352 54.95835 0)
			(layer "F.Fab")
			(hide yes)
			(effects
				(font
					(size 1 1)
					(thickness 0.15)
				)
			)
		)
		(property "Voltage" "50V"
			(at 257.959352 54.95835 0)
			(layer "F.Fab")
			(hide yes)
			(effects
				(font
					(size 1 1)
					(thickness 0.15)
				)
			)
		)
		(sheetname "/Ethernet/")
		(sheetfile "ethernet.kicad_sch")
		(attr smd)
		(fp_rect
			(start -0.9659 -0.481258)
			(end 0.9649 0.458742)
			(stroke
				(width 0.05)
				(type solid)
			)
			(fill no)
			(layer "F.CrtYd")
		)
		(fp_line
			(start 0.499 -0.25)
			(end 0.499 0.248)
			(stroke
				(width 0.15)
				(type solid)
			)
			(layer "F.Fab")
		)
		(fp_line
			(start -0.499 -0.25)
			(end 0.499 -0.25)
			(stroke
				(width 0.15)
				(type solid)
			)
			(layer "F.Fab")
		)
		(fp_line
			(start 0.499 0.248)
			(end -0.499 0.248)
			(stroke
				(width 0.15)
				(type solid)
			)
			(layer "F.Fab")
		)
		(fp_line
			(start -0.499 0.248)
			(end -0.499 -0.25)
			(stroke
				(width 0.15)
				(type solid)
			)
			(layer "F.Fab")
		)
		(pad "1" smd roundrect
			(at -0.484 0 90)
			(size 0.59 0.64)
			(layers "F.Cu" "F.Mask" "F.Paste")
			(roundrect_rratio 0.25)
			(net 1 "GND")
			(pintype "passive")
		)
		(pad "2" smd roundrect
			(at 0.484 0 90)
			(size 0.59 0.64)
			(layers "F.Cu" "F.Mask" "F.Paste")
			(roundrect_rratio 0.25)
			(net 133 "/Ethernet/AVDDL_PLL")
			(pintype "passive")
		)
	)
	(footprint "antmicro-footprints:C_0402_1005Metric"
		(layer "F.Cu")
		(at 88.500501 151.733157 90)
		(descr "Capacitor SMD 0402")
		(tags "capacitor SMD 0402")
		(property "Reference" "C149"
			(at 0 -0.699 90)
			(layer "F.SilkS")
			(hide yes)
			(effects
				(font
					(size 0.7 0.7)
					(thickness 0.15)
				)
				(justify left bottom)
			)
		)
		(property "Value" "C_470n_0402"
			(at -1.022927 2.155213 90)
			(layer "F.Fab")
			(effects
				(font
					(size 0.7 0.7)
					(thickness 0.15)
				)
				(justify left bottom)
			)
		)
		(property "Datasheet" "https://product.tdk.com/en/search/capacitor/ceramic/mlcc/info?part_no=C1005X5R1E474M050BB"
			(at 0 0 90)
			(layer "F.Fab")
			(hide yes)
			(effects
				(font
					(size 1.27 1.27)
					(thickness 0.15)
				)
			)
		)
		(property "Author" "Antmicro"
			(at 240.233658 63.232656 0)
			(layer "F.Fab")
			(hide yes)
			(effects
				(font
					(size 1 1)
					(thickness 0.15)
				)
			)
		)
		(property "Dielectric" ""
			(at 240.233658 63.232656 0)
			(layer "F.Fab")
			(hide yes)
			(effects
				(font
					(size 1 1)
					(thickness 0.15)
				)
			)
		)
		(property "License" "Apache-2.0"
			(at 240.233658 63.232656 0)
			(layer "F.Fab")
			(hide yes)
			(effects
				(font
					(size 1 1)
					(thickness 0.15)
				)
			)
		)
		(property "MPN" "C1005X5R1E474M050BB"
			(at 240.233658 63.232656 0)
			(layer "F.Fab")
			(hide yes)
			(effects
				(font
					(size 1 1)
					(thickness 0.15)
				)
			)
		)
		(property "Manufacturer" "TDK"
			(at 240.233658 63.232656 0)
			(layer "F.Fab")
			(hide yes)
			(effects
				(font
					(size 1 1)
					(thickness 0.15)
				)
			)
		)
		(property "Val" "470n"
			(at 240.233658 63.232656 0)
			(layer "F.Fab")
			(hide yes)
			(effects
				(font
					(size 1 1)
					(thickness 0.15)
				)
			)
		)
		(property "Voltage" ""
			(at 240.233658 63.232656 0)
			(layer "F.Fab")
			(hide yes)
			(effects
				(font
					(size 1 1)
					(thickness 0.15)
				)
			)
		)
		(sheetname "/Ethernet/")
		(sheetfile "ethernet.kicad_sch")
		(attr smd)
		(fp_rect
			(start -0.9659 -0.481258)
			(end 0.9649 0.458742)
			(stroke
				(width 0.05)
				(type solid)
			)
			(fill no)
			(layer "F.CrtYd")
		)
		(fp_line
			(start 0.499 -0.25)
			(end 0.499 0.248)
			(stroke
				(width 0.15)
				(type solid)
			)
			(layer "F.Fab")
		)
		(fp_line
			(start -0.499 -0.25)
			(end 0.499 -0.25)
			(stroke
				(width 0.15)
				(type solid)
			)
			(layer "F.Fab")
		)
		(fp_line
			(start 0.499 0.248)
			(end -0.499 0.248)
			(stroke
				(width 0.15)
				(type solid)
			)
			(layer "F.Fab")
		)
		(fp_line
			(start -0.499 0.248)
			(end -0.499 -0.25)
			(stroke
				(width 0.15)
				(type solid)
			)
			(layer "F.Fab")
		)
		(pad "1" smd roundrect
			(at -0.484 0 90)
			(size 0.59 0.64)
			(layers "F.Cu" "F.Mask" "F.Paste")
			(roundrect_rratio 0.25)
			(net 199 "+1V2")
			(pintype "passive")
		)
		(pad "2" smd roundrect
			(at 0.484 0 90)
			(size 0.59 0.64)
			(layers "F.Cu" "F.Mask" "F.Paste")
			(roundrect_rratio 0.25)
			(net 1 "GND")
			(pintype "passive")
		)
	)
)
